FILE_TYPE = CONNECTIVITY;
{Allegro Design Entry HDL 17.2-2016 S081 (4005846) 1/11/2022}
"PAGE_NUMBER" = 10;
0"NC";
1"M_A_CPU0_SA_DQ<31:0>";
2"M_A_CPU0_SB_DQ<31:0>";
3"M_A_CPU0_SB_CB<7:0>";
4"M_A_CPU0_SA_DQS_DP<9:0>";
5"M_A_CPU0_SA_DQS_DN<9:0>";
6"M_A_CPU0_SB_DQS_DP<9:0>";
7"M_A_CPU0_SB_DQS_DN<9:0>";
8"M_A_CPU0_SA_CA<6:0>";
9"M_A_CPU0_SB_CA<6:0>";
10"M_A_CPU0_SA_CB<7:0>";
11"M_A_CPU0_ALERT_N";
12"TP_M_A_CPU0_SA_TEST39A";
13"TP_M_A_CPU0_SA_TEST40";
14"M_A_CPU0_ALERT_R_N";
15"M_A_CPU0_CLK_DP<0>";
16"M_A_CPU0_CLK_DN<0>";
17"M_A_CPU0_SA_CS_N<0>";
18"M_A_CPU0_SA_CS_N<1>";
19"M_A_CPU0_SA_RSP<0>";
20"M_A_CPU0_SB_CS_N<0>";
21"M_A_CPU0_SA_PAR";
22"M_A_CPU0_SB_CS_N<1>";
23"M_A_CPU0_SB_RSP<0>";
24"M_A_CPU0_SB_PAR";
25"M_A_CPU0_RESET_N";
26"M_A_CPU0_SB_CA<6>";
27"M_A_CPU0_SA_CA<6>";
28"M_A_CPU0_SB_CA<5>";
29"M_A_CPU0_SA_CA<5>";
30"M_A_CPU0_SB_CA<4>";
31"M_A_CPU0_SA_CA<4>";
32"M_A_CPU0_SB_CA<3>";
33"M_A_CPU0_SA_CA<3>";
34"M_A_CPU0_SB_CA<2>";
35"M_A_CPU0_SA_CA<2>";
36"M_A_CPU0_SB_CA<1>";
37"M_A_CPU0_SA_CA<1>";
38"M_A_CPU0_SB_CA<0>";
39"M_A_CPU0_SA_CA<0>";
40"M_A_CPU0_SB_DQS_DN<4>";
41"M_A_CPU0_SB_DQS_DN<3>";
42"M_A_CPU0_SB_DQS_DN<2>";
43"M_A_CPU0_SB_DQS_DN<1>";
44"M_A_CPU0_SB_DQS_DN<0>";
45"M_A_CPU0_SB_DQS_DN<9>";
46"M_A_CPU0_SB_DQS_DN<8>";
47"M_A_CPU0_SB_DQS_DN<7>";
48"M_A_CPU0_SB_DQS_DN<6>";
49"M_A_CPU0_SB_DQS_DN<5>";
50"M_A_CPU0_SB_DQS_DP<9>";
51"M_A_CPU0_SB_DQS_DP<8>";
52"M_A_CPU0_SB_DQS_DP<7>";
53"M_A_CPU0_SB_DQS_DP<6>";
54"M_A_CPU0_SB_DQS_DP<5>";
55"M_A_CPU0_SB_DQS_DP<0>";
56"M_A_CPU0_SB_DQS_DP<4>";
57"M_A_CPU0_SB_DQS_DP<3>";
58"M_A_CPU0_SB_DQS_DP<2>";
59"M_A_CPU0_SB_DQS_DP<1>";
60"M_A_CPU0_SA_DQS_DN<9>";
61"M_A_CPU0_SA_DQS_DN<8>";
62"M_A_CPU0_SA_DQS_DN<6>";
63"M_A_CPU0_SA_DQS_DN<5>";
64"M_A_CPU0_SA_DQS_DN<4>";
65"M_A_CPU0_SA_DQS_DN<3>";
66"M_A_CPU0_SA_DQS_DN<2>";
67"M_A_CPU0_SA_DQS_DN<7>";
68"M_A_CPU0_SA_DQS_DN<1>";
69"M_A_CPU0_SA_DQS_DN<0>";
70"M_A_CPU0_SA_DQS_DP<6>";
71"M_A_CPU0_SA_DQS_DP<5>";
72"M_A_CPU0_SA_DQS_DP<9>";
73"M_A_CPU0_SA_DQS_DP<8>";
74"M_A_CPU0_SA_DQS_DP<7>";
75"M_A_CPU0_SA_DQS_DP<4>";
76"M_A_CPU0_SA_DQS_DP<3>";
77"M_A_CPU0_SA_DQS_DP<2>";
78"M_A_CPU0_SA_DQS_DP<1>";
79"M_A_CPU0_SA_DQS_DP<0>";
80"M_A_CPU0_SB_CB<7>";
81"M_A_CPU0_SB_CB<6>";
82"M_A_CPU0_SB_CB<5>";
83"M_A_CPU0_SB_CB<4>";
84"M_A_CPU0_SB_CB<3>";
85"M_A_CPU0_SB_CB<2>";
86"M_A_CPU0_SB_CB<1>";
87"M_A_CPU0_SA_CB<7>";
88"M_A_CPU0_SA_CB<6>";
89"M_A_CPU0_SB_CB<0>";
90"M_A_CPU0_SA_CB<5>";
91"M_A_CPU0_SA_CB<4>";
92"M_A_CPU0_SA_CB<3>";
93"M_A_CPU0_SA_CB<2>";
94"M_A_CPU0_SA_CB<1>";
95"M_A_CPU0_SA_CB<0>";
96"M_A_CPU0_SB_DQ<28>";
97"M_A_CPU0_SB_DQ<27>";
98"M_A_CPU0_SB_DQ<26>";
99"M_A_CPU0_SB_DQ<25>";
100"M_A_CPU0_SB_DQ<24>";
101"M_A_CPU0_SB_DQ<23>";
102"M_A_CPU0_SB_DQ<31>";
103"M_A_CPU0_SB_DQ<30>";
104"M_A_CPU0_SB_DQ<29>";
105"M_A_CPU0_SB_DQ<17>";
106"M_A_CPU0_SB_DQ<16>";
107"M_A_CPU0_SB_DQ<15>";
108"M_A_CPU0_SB_DQ<14>";
109"M_A_CPU0_SB_DQ<22>";
110"M_A_CPU0_SB_DQ<21>";
111"M_A_CPU0_SB_DQ<20>";
112"M_A_CPU0_SB_DQ<19>";
113"M_A_CPU0_SB_DQ<18>";
114"M_A_CPU0_SB_DQ<13>";
115"M_A_CPU0_SB_DQ<12>";
116"M_A_CPU0_SB_DQ<11>";
117"M_A_CPU0_SB_DQ<10>";
118"M_A_CPU0_SB_DQ<9>";
119"M_A_CPU0_SB_DQ<8>";
120"M_A_CPU0_SB_DQ<7>";
121"M_A_CPU0_SB_DQ<6>";
122"M_A_CPU0_SB_DQ<5>";
123"M_A_CPU0_SB_DQ<2>";
124"M_A_CPU0_SB_DQ<1>";
125"M_A_CPU0_SB_DQ<0>";
126"M_A_CPU0_SA_DQ<29>";
127"M_A_CPU0_SA_DQ<28>";
128"M_A_CPU0_SA_DQ<27>";
129"M_A_CPU0_SA_DQ<31>";
130"M_A_CPU0_SA_DQ<30>";
131"M_A_CPU0_SB_DQ<4>";
132"M_A_CPU0_SB_DQ<3>";
133"M_A_CPU0_SA_DQ<19>";
134"M_A_CPU0_SA_DQ<18>";
135"M_A_CPU0_SA_DQ<26>";
136"M_A_CPU0_SA_DQ<25>";
137"M_A_CPU0_SA_DQ<24>";
138"M_A_CPU0_SA_DQ<23>";
139"M_A_CPU0_SA_DQ<22>";
140"M_A_CPU0_SA_DQ<21>";
141"M_A_CPU0_SA_DQ<20>";
142"M_A_CPU0_SA_DQ<17>";
143"M_A_CPU0_SA_DQ<16>";
144"M_A_CPU0_SA_DQ<15>";
145"M_A_CPU0_SA_DQ<14>";
146"M_A_CPU0_SA_DQ<13>";
147"M_A_CPU0_SA_DQ<9>";
148"M_A_CPU0_SA_DQ<12>";
149"M_A_CPU0_SA_DQ<11>";
150"M_A_CPU0_SA_DQ<10>";
151"M_A_CPU0_SA_DQ<3>";
152"M_A_CPU0_SA_DQ<2>";
153"M_A_CPU0_SA_DQ<1>";
154"M_A_CPU0_SA_DQ<0>";
155"M_A_CPU0_SA_DQ<8>";
156"M_A_CPU0_SA_DQ<7>";
157"M_A_CPU0_SA_DQ<6>";
158"M_A_CPU0_SA_DQ<5>";
159"M_A_CPU0_SA_DQ<4>";
%"GENOA_SP5"
"1","(-4350,3700)","0","pure_quanta","I200";
;
LOCATION"U25"
$SEC"1"
CDS_SEC"1"
PART_TYPE"SMLF"
MATERIAL"IO"
VALUE"SOCKET6096_13568-001"
PART_NUMBER"DGA^6000030"
CDS_LIB"pure_quanta"
NEEDS_NO_SIZE"TRUE"
CDS_LMAN_SYM_OUTLINE"-650,2500,650,-2500";
"TEST40"
$PN"C60"13;
"TEST39A"
$PN"BF72"12;
"MA1_CLK_L"
$PN"BG74"0;
"MA0_CLK_L"
$PN"BD74"16;
"MA1_CLK_H"
$PN"BF74"0;
"MAB_DQS_H9"
$PN"BV74"50;
"MA0_CLK_H"
$PN"BC74"15;
"MAB_PAR"
$PN"BL74"24;
"MAA_PAR"
$PN"BC73"21;
"MAA0_CS_L0"
$PN"AV74"17;
"MAA_DATA3"
$PN"G73"151;
"MAA_DQS_H6"
$PN"R73"70;
"MAB_CA6"
$PN"BK74"26;
"MAB_DATA2"
$PN"CC74"123;
"MAB_DATA17"
$PN"CR73"105;
"MAB_DATA28"
$PN"DD74"96;
"MAB_DQS_H0"
$PN"CD74"55;
"MAB_DQS_L4"
$PN"BW73"40;
"MAA_CA6"
$PN"BB72"27;
"MAA_DATA2"
$PN"F74"152;
"MAA_DQS_H5"
$PN"J73"71;
"MAA_DQS_L9"
$PN"AM72"60;
"MAB1_RSP_L"
$PN"BR74"0;
"MAB_CA5"
$PN"BK72"28;
"MAB_CHECK7"
$PN"BV72"80;
"MAB_DATA1"
$PN"CC73"124;
"MAB_DATA16"
$PN"CP74"106;
"MAB_DATA27"
$PN"DB72"97;
"MAB_DQS_L3"
$PN"DC74"41;
"MAA_CA5"
$PN"BB74"29;
"MAA_DATA1"
$PN"F72"153;
"MAA_DQS_H4"
$PN"AL74"75;
"MAA_DQS_L8"
$PN"AF72"61;
"MAB0_RSP_L"
$PN"BP74"23;
"MAB_CA4"
$PN"BJ73"30;
"MAB_CHECK6"
$PN"BU74"81;
"MAB_DATA0"
$PN"CB74"125;
"MAB_DATA15"
$PN"CP72"107;
"MAB_DATA26"
$PN"DA74"98;
"MAB_DQS_L2"
$PN"CU74"42;
"MAA_CA4"
$PN"BA74"31;
"MAA_DATA0"
$PN"E74"154;
"MAA_DQS_H3"
$PN"AE74"76;
"MAA_DQS_L7"
$PN"Y72"67;
"MAB_CA3"
$PN"BJ74"32;
"MAB_CHECK5"
$PN"BU73"82;
"MAB_DATA14"
$PN"CN74"108;
"MAB_DATA25"
$PN"DA73"99;
"MAB_DQS_L1"
$PN"CL74"43;
"MAA_CA3"
$PN"BA73"33;
"MAA_DATA19"
$PN"W73"133;
"MAA_DQS_H2"
$PN"W74"77;
"MAA_DQS_L6"
$PN"P72"62;
"MAB_CA2"
$PN"BH74"34;
"MAB_CHECK4"
$PN"BT74"83;
"MAB_DATA13"
$PN"CN73"114;
"MAB_DATA24"
$PN"CY74"100;
"MAB_DQS_L0"
$PN"CE74"44;
"MAA_CA2"
$PN"AY72"35;
"MAA_DATA18"
$PN"V74"134;
"MAA_DATA29"
$PN"AH72"126;
"MAA_DQS_H1"
$PN"N74"78;
"MAA_DQS_L5"
$PN"H72"63;
"MAB_CA1"
$PN"BH72"36;
"MAB_CHECK3"
$PN"CB72"84;
"MAB_DATA12"
$PN"CM74"115;
"MAB_DATA23"
$PN"CY72"101;
"MAA_CA1"
$PN"AY74"37;
"MAA_DATA17"
$PN"V72"142;
"MAA_DATA28"
$PN"AG74"127;
"MAA_DQS_H0"
$PN"G74"79;
"MAA_DQS_L4"
$PN"AM74"64;
"MAB_CA0"
$PN"BG73"38;
"MAB_CHECK2"
$PN"CA74"85;
"MAB_DATA11"
$PN"CK72"116;
"MAB_DATA22"
$PN"CW74"109;
"MAA1_RSP_L"
$PN"BP72"0;
"MAA_CA0"
$PN"AW74"39;
"MAA_CHECK7"
$PN"AR73"87;
"MAA_DATA16"
$PN"U74"143;
"MAA_DATA27"
$PN"AE73"128;
"MAA_DQS_L3"
$PN"AF74"65;
"MAB_CHECK1"
$PN"CA73"86;
"MAB_DATA10"
$PN"CJ74"117;
"MAB_DATA21"
$PN"CW73"110;
"MAA0_RSP_L"
$PN"BN73"19;
"MAA_CHECK6"
$PN"AP74"88;
"MAA_DATA15"
$PN"U73"144;
"MAA_DATA26"
$PN"AD74"135;
"MAA_DQS_L2"
$PN"Y74"66;
"MAB_CHECK0"
$PN"BY74"89;
"MAB_DATA20"
$PN"CV74"111;
"MAB_DATA31"
$PN"DF74"102;
"MAA_CHECK5"
$PN"AP72"90;
"MAA_DATA14"
$PN"T74"145;
"MAA_DATA25"
$PN"AD72"136;
"MAA_DQS_L1"
$PN"P74"68;
"MAB1_CS_L1"
$PN"BM74"0;
"MAB_DATA30"
$PN"DE74"103;
"MAB_DQS_H8"
$PN"DD72"51;
"MAA_CHECK4"
$PN"AN74"91;
"MAA_DATA13"
$PN"T72"146;
"MAA_DATA24"
$PN"AC74"137;
"MAA_DQS_L0"
$PN"H74"69;
"MAB0_CS_L1"
$PN"BN74"22;
"MAB1_CS_L0"
$PN"BL73"0;
"MAB_DATA9"
$PN"CJ73"118;
"MAB_DQS_H7"
$PN"CV72"52;
"MAA_CHECK3"
$PN"AL73"92;
"MAA_DATA9"
$PN"M72"147;
"MAA_DATA12"
$PN"R74"148;
"MAA_DATA23"
$PN"AC73"138;
"MAB0_CS_L0"
$PN"BM72"20;
"MAB_DATA8"
$PN"CH74"119;
"MAB_DQS_H6"
$PN"CM72"53;
"MAA_CHECK2"
$PN"AK74"93;
"MAA_DATA8"
$PN"L74"155;
"MAA_DATA11"
$PN"N73"149;
"MAA_DATA22"
$PN"AB74"139;
"MAB_DATA7"
$PN"CH72"120;
"MAB_DQS_H5"
$PN"CF72"54;
"MAB_DQS_L9"
$PN"BW74"45;
"MAA_CHECK1"
$PN"AK72"94;
"MAA_DATA7"
$PN"L73"156;
"MAA_DATA10"
$PN"M74"150;
"MAA_DATA21"
$PN"AB72"140;
"MAB_DATA6"
$PN"CG74"121;
"MAB_DQS_H4"
$PN"BY72"56;
"MAB_DQS_L8"
$PN"DC73"46;
"MAA_CHECK0"
$PN"AJ74"95;
"MAA_DATA6"
$PN"K74"157;
"MAA_DATA20"
$PN"AA74"141;
"MAA_DATA31"
$PN"AJ73"129;
"MAA_DQS_H9"
$PN"AN73"72;
"MAB_DATA5"
$PN"CG73"122;
"MAB_DQS_H3"
$PN"DB74"57;
"MAB_DQS_L7"
$PN"CU73"47;
"MAA1_CS_L1"
$PN"AV72"0;
"MAA_DATA5"
$PN"K72"158;
"MAA_DATA30"
$PN"AH74"130;
"MAA_DQS_H8"
$PN"AG73"73;
"MAB_DATA4"
$PN"CF74"131;
"MAB_DATA19"
$PN"CT72"112;
"MAB_DQS_H2"
$PN"CT74"58;
"MAB_DQS_L6"
$PN"CL73"48;
"MAA0_CS_L1"
$PN"AW73"18;
"MAA1_CS_L0"
$PN"AU74"0;
"MAA_DATA4"
$PN"J74"159;
"MAA_DQS_H7"
$PN"AA73"74;
"MAB_DATA3"
$PN"CD72"132;
"MAB_DATA18"
$PN"CR74"113;
"MAB_DATA29"
$PN"DE73"104;
"MAB_DQS_H1"
$PN"CK74"59;
"MAB_DQS_L5"
$PN"CE73"49;
"MA_RESET_L"
$PN"AT74"25;
"MA_ALERT_L"
$PN"AR74"14;
%"TAP"
"1","(-3025,6100)","0","mstr_standard","I683";
;
CDS_LIB"mstr_standard"
BODY_TYPE"PLUMBING"
HDL_TAP"TRUE";
"B \NAC \NWC"1;
"S \NAC"
BN"0"154;
%"TAP"
"1","(-3025,5950)","0","mstr_standard","I684";
;
CDS_LIB"mstr_standard"
BODY_TYPE"PLUMBING"
HDL_TAP"TRUE";
"B \NAC \NWC"1;
"S \NAC"
BN"3"151;
%"TAP"
"1","(-3025,6000)","0","mstr_standard","I685";
;
CDS_LIB"mstr_standard"
BODY_TYPE"PLUMBING"
HDL_TAP"TRUE";
"B \NAC \NWC"1;
"S \NAC"
BN"2"152;
%"TAP"
"1","(-3025,6050)","0","mstr_standard","I686";
;
CDS_LIB"mstr_standard"
BODY_TYPE"PLUMBING"
HDL_TAP"TRUE";
"B \NAC \NWC"1;
"S \NAC"
BN"1"153;
%"TAP"
"1","(-3025,5900)","0","mstr_standard","I687";
;
CDS_LIB"mstr_standard"
BODY_TYPE"PLUMBING"
HDL_TAP"TRUE";
"B \NAC \NWC"1;
"S \NAC"
BN"4"159;
%"TAP"
"1","(-3025,5850)","0","mstr_standard","I688";
;
CDS_LIB"mstr_standard"
BODY_TYPE"PLUMBING"
HDL_TAP"TRUE";
"B \NAC \NWC"1;
"S \NAC"
BN"5"158;
%"TAP"
"1","(-3025,5650)","0","mstr_standard","I689";
;
CDS_LIB"mstr_standard"
BODY_TYPE"PLUMBING"
HDL_TAP"TRUE";
"B \NAC \NWC"1;
"S \NAC"
BN"8"155;
%"TAP"
"1","(-3025,5750)","0","mstr_standard","I690";
;
CDS_LIB"mstr_standard"
BODY_TYPE"PLUMBING"
HDL_TAP"TRUE";
"B \NAC \NWC"1;
"S \NAC"
BN"7"156;
%"TAP"
"1","(-3025,5800)","0","mstr_standard","I691";
;
CDS_LIB"mstr_standard"
BODY_TYPE"PLUMBING"
HDL_TAP"TRUE";
"B \NAC \NWC"1;
"S \NAC"
BN"6"157;
%"TAP"
"1","(-3025,5600)","0","mstr_standard","I692";
;
CDS_LIB"mstr_standard"
BODY_TYPE"PLUMBING"
HDL_TAP"TRUE";
"B \NAC \NWC"1;
"S \NAC"
BN"9"147;
%"TAP"
"1","(-3025,5400)","0","mstr_standard","I693";
;
CDS_LIB"mstr_standard"
BODY_TYPE"PLUMBING"
HDL_TAP"TRUE";
"B \NAC \NWC"1;
"S \NAC"
BN"13"146;
%"TAP"
"1","(-3025,5450)","0","mstr_standard","I694";
;
CDS_LIB"mstr_standard"
BODY_TYPE"PLUMBING"
HDL_TAP"TRUE";
"B \NAC \NWC"1;
"S \NAC"
BN"12"148;
%"TAP"
"1","(-3025,5500)","0","mstr_standard","I695";
;
CDS_LIB"mstr_standard"
BODY_TYPE"PLUMBING"
HDL_TAP"TRUE";
"B \NAC \NWC"1;
"S \NAC"
BN"11"149;
%"TAP"
"1","(-3025,5550)","0","mstr_standard","I696";
;
CDS_LIB"mstr_standard"
BODY_TYPE"PLUMBING"
HDL_TAP"TRUE";
"B \NAC \NWC"1;
"S \NAC"
BN"10"150;
%"TAP"
"1","(-3025,5350)","0","mstr_standard","I697";
;
CDS_LIB"mstr_standard"
BODY_TYPE"PLUMBING"
HDL_TAP"TRUE";
"B \NAC \NWC"1;
"S \NAC"
BN"14"145;
%"TAP"
"1","(-3025,5200)","0","mstr_standard","I698";
;
CDS_LIB"mstr_standard"
BODY_TYPE"PLUMBING"
HDL_TAP"TRUE";
"B \NAC \NWC"1;
"S \NAC"
BN"16"143;
%"TAP"
"1","(-3025,5150)","0","mstr_standard","I699";
;
CDS_LIB"mstr_standard"
BODY_TYPE"PLUMBING"
HDL_TAP"TRUE";
"B \NAC \NWC"1;
"S \NAC"
BN"17"142;
%"TAP"
"1","(-3025,5300)","0","mstr_standard","I700";
;
CDS_LIB"mstr_standard"
BODY_TYPE"PLUMBING"
HDL_TAP"TRUE";
"B \NAC \NWC"1;
"S \NAC"
BN"15"144;
%"TAP"
"1","(-3025,5050)","0","mstr_standard","I701";
;
CDS_LIB"mstr_standard"
BODY_TYPE"PLUMBING"
HDL_TAP"TRUE";
"B \NAC \NWC"1;
"S \NAC"
BN"19"133;
%"TAP"
"1","(-3025,5100)","0","mstr_standard","I702";
;
CDS_LIB"mstr_standard"
BODY_TYPE"PLUMBING"
HDL_TAP"TRUE";
"B \NAC \NWC"1;
"S \NAC"
BN"18"134;
%"TAP"
"1","(-3025,4950)","0","mstr_standard","I704";
;
CDS_LIB"mstr_standard"
BODY_TYPE"PLUMBING"
HDL_TAP"TRUE";
"B \NAC \NWC"1;
"S \NAC"
BN"21"140;
%"TAP"
"1","(-3025,4900)","0","mstr_standard","I705";
;
CDS_LIB"mstr_standard"
BODY_TYPE"PLUMBING"
HDL_TAP"TRUE";
"B \NAC \NWC"1;
"S \NAC"
BN"22"139;
%"TAP"
"1","(-3025,5000)","0","mstr_standard","I706";
;
CDS_LIB"mstr_standard"
BODY_TYPE"PLUMBING"
HDL_TAP"TRUE";
"B \NAC \NWC"1;
"S \NAC"
BN"20"141;
%"TAP"
"1","(-3025,4850)","0","mstr_standard","I707";
;
CDS_LIB"mstr_standard"
BODY_TYPE"PLUMBING"
HDL_TAP"TRUE";
"B \NAC \NWC"1;
"S \NAC"
BN"23"138;
%"TAP"
"1","(-3025,4650)","0","mstr_standard","I708";
;
CDS_LIB"mstr_standard"
BODY_TYPE"PLUMBING"
HDL_TAP"TRUE";
"B \NAC \NWC"1;
"S \NAC"
BN"26"135;
%"TAP"
"1","(-3025,4700)","0","mstr_standard","I709";
;
CDS_LIB"mstr_standard"
BODY_TYPE"PLUMBING"
HDL_TAP"TRUE";
"B \NAC \NWC"1;
"S \NAC"
BN"25"136;
%"TAP"
"1","(-3025,4750)","0","mstr_standard","I710";
;
CDS_LIB"mstr_standard"
BODY_TYPE"PLUMBING"
HDL_TAP"TRUE";
"B \NAC \NWC"1;
"S \NAC"
BN"24"137;
%"TAP"
"1","(-3025,4550)","0","mstr_standard","I711";
;
CDS_LIB"mstr_standard"
BODY_TYPE"PLUMBING"
HDL_TAP"TRUE";
"B \NAC \NWC"1;
"S \NAC"
BN"28"127;
%"TAP"
"1","(-3025,4600)","0","mstr_standard","I712";
;
CDS_LIB"mstr_standard"
BODY_TYPE"PLUMBING"
HDL_TAP"TRUE";
"B \NAC \NWC"1;
"S \NAC"
BN"27"128;
%"TAP"
"1","(-3025,4400)","0","mstr_standard","I713";
;
CDS_LIB"mstr_standard"
BODY_TYPE"PLUMBING"
HDL_TAP"TRUE";
"B \NAC \NWC"1;
"S \NAC"
BN"31"129;
%"TAP"
"1","(-3025,4450)","0","mstr_standard","I714";
;
CDS_LIB"mstr_standard"
BODY_TYPE"PLUMBING"
HDL_TAP"TRUE";
"B \NAC \NWC"1;
"S \NAC"
BN"30"130;
%"TAP"
"1","(-3025,4500)","0","mstr_standard","I715";
;
CDS_LIB"mstr_standard"
BODY_TYPE"PLUMBING"
HDL_TAP"TRUE";
"B \NAC \NWC"1;
"S \NAC"
BN"29"126;
%"TAP"
"1","(-3025,4300)","0","mstr_standard","I716";
;
CDS_LIB"mstr_standard"
BODY_TYPE"PLUMBING"
HDL_TAP"TRUE";
"B \NAC \NWC"2;
"S \NAC"
BN"0"125;
%"TAP"
"1","(-3025,4150)","0","mstr_standard","I717";
;
CDS_LIB"mstr_standard"
BODY_TYPE"PLUMBING"
HDL_TAP"TRUE";
"B \NAC \NWC"2;
"S \NAC"
BN"3"132;
%"TAP"
"1","(-3025,4200)","0","mstr_standard","I718";
;
CDS_LIB"mstr_standard"
BODY_TYPE"PLUMBING"
HDL_TAP"TRUE";
"B \NAC \NWC"2;
"S \NAC"
BN"2"123;
%"TAP"
"1","(-3025,4250)","0","mstr_standard","I719";
;
CDS_LIB"mstr_standard"
BODY_TYPE"PLUMBING"
HDL_TAP"TRUE";
"B \NAC \NWC"2;
"S \NAC"
BN"1"124;
%"TAP"
"1","(-3025,4100)","0","mstr_standard","I720";
;
CDS_LIB"mstr_standard"
BODY_TYPE"PLUMBING"
HDL_TAP"TRUE";
"B \NAC \NWC"2;
"S \NAC"
BN"4"131;
%"TAP"
"1","(-3025,4050)","0","mstr_standard","I721";
;
CDS_LIB"mstr_standard"
BODY_TYPE"PLUMBING"
HDL_TAP"TRUE";
"B \NAC \NWC"2;
"S \NAC"
BN"5"122;
%"TAP"
"1","(-3025,3850)","0","mstr_standard","I722";
;
CDS_LIB"mstr_standard"
BODY_TYPE"PLUMBING"
HDL_TAP"TRUE";
"B \NAC \NWC"2;
"S \NAC"
BN"8"119;
%"TAP"
"1","(-3025,3950)","0","mstr_standard","I723";
;
CDS_LIB"mstr_standard"
BODY_TYPE"PLUMBING"
HDL_TAP"TRUE";
"B \NAC \NWC"2;
"S \NAC"
BN"7"120;
%"TAP"
"1","(-3025,4000)","0","mstr_standard","I724";
;
CDS_LIB"mstr_standard"
BODY_TYPE"PLUMBING"
HDL_TAP"TRUE";
"B \NAC \NWC"2;
"S \NAC"
BN"6"121;
%"TAP"
"1","(-3025,3800)","0","mstr_standard","I725";
;
CDS_LIB"mstr_standard"
BODY_TYPE"PLUMBING"
HDL_TAP"TRUE";
"B \NAC \NWC"2;
"S \NAC"
BN"9"118;
%"TAP"
"1","(-3025,3600)","0","mstr_standard","I726";
;
CDS_LIB"mstr_standard"
BODY_TYPE"PLUMBING"
HDL_TAP"TRUE";
"B \NAC \NWC"2;
"S \NAC"
BN"13"114;
%"TAP"
"1","(-3025,3700)","0","mstr_standard","I727";
;
CDS_LIB"mstr_standard"
BODY_TYPE"PLUMBING"
HDL_TAP"TRUE";
"B \NAC \NWC"2;
"S \NAC"
BN"11"116;
%"TAP"
"1","(-3025,3650)","0","mstr_standard","I728";
;
CDS_LIB"mstr_standard"
BODY_TYPE"PLUMBING"
HDL_TAP"TRUE";
"B \NAC \NWC"2;
"S \NAC"
BN"12"115;
%"TAP"
"1","(-3025,3750)","0","mstr_standard","I729";
;
CDS_LIB"mstr_standard"
BODY_TYPE"PLUMBING"
HDL_TAP"TRUE";
"B \NAC \NWC"2;
"S \NAC"
BN"10"117;
%"TAP"
"1","(-3025,3550)","0","mstr_standard","I730";
;
CDS_LIB"mstr_standard"
BODY_TYPE"PLUMBING"
HDL_TAP"TRUE";
"B \NAC \NWC"2;
"S \NAC"
BN"14"108;
%"TAP"
"1","(-3025,3400)","0","mstr_standard","I731";
;
CDS_LIB"mstr_standard"
BODY_TYPE"PLUMBING"
HDL_TAP"TRUE";
"B \NAC \NWC"2;
"S \NAC"
BN"16"106;
%"TAP"
"1","(-3025,3350)","0","mstr_standard","I732";
;
CDS_LIB"mstr_standard"
BODY_TYPE"PLUMBING"
HDL_TAP"TRUE";
"B \NAC \NWC"2;
"S \NAC"
BN"17"105;
%"TAP"
"1","(-3025,3500)","0","mstr_standard","I733";
;
CDS_LIB"mstr_standard"
BODY_TYPE"PLUMBING"
HDL_TAP"TRUE";
"B \NAC \NWC"2;
"S \NAC"
BN"15"107;
%"TAP"
"1","(-3025,3300)","0","mstr_standard","I734";
;
CDS_LIB"mstr_standard"
BODY_TYPE"PLUMBING"
HDL_TAP"TRUE";
"B \NAC \NWC"2;
"S \NAC"
BN"18"113;
%"TAP"
"1","(-3025,3100)","0","mstr_standard","I735";
;
CDS_LIB"mstr_standard"
BODY_TYPE"PLUMBING"
HDL_TAP"TRUE";
"B \NAC \NWC"2;
"S \NAC"
BN"22"109;
%"TAP"
"1","(-3025,3150)","0","mstr_standard","I736";
;
CDS_LIB"mstr_standard"
BODY_TYPE"PLUMBING"
HDL_TAP"TRUE";
"B \NAC \NWC"2;
"S \NAC"
BN"21"110;
%"TAP"
"1","(-3025,3200)","0","mstr_standard","I737";
;
CDS_LIB"mstr_standard"
BODY_TYPE"PLUMBING"
HDL_TAP"TRUE";
"B \NAC \NWC"2;
"S \NAC"
BN"20"111;
%"TAP"
"1","(-3025,3250)","0","mstr_standard","I738";
;
CDS_LIB"mstr_standard"
BODY_TYPE"PLUMBING"
HDL_TAP"TRUE";
"B \NAC \NWC"2;
"S \NAC"
BN"19"112;
%"TAP"
"1","(-3025,3050)","0","mstr_standard","I739";
;
CDS_LIB"mstr_standard"
BODY_TYPE"PLUMBING"
HDL_TAP"TRUE";
"B \NAC \NWC"2;
"S \NAC"
BN"23"101;
%"TAP"
"1","(-3025,2900)","0","mstr_standard","I742";
;
CDS_LIB"mstr_standard"
BODY_TYPE"PLUMBING"
HDL_TAP"TRUE";
"B \NAC \NWC"2;
"S \NAC"
BN"25"99;
%"TAP"
"1","(-3025,2850)","0","mstr_standard","I743";
;
CDS_LIB"mstr_standard"
BODY_TYPE"PLUMBING"
HDL_TAP"TRUE";
"B \NAC \NWC"2;
"S \NAC"
BN"26"98;
%"TAP"
"1","(-3025,2950)","0","mstr_standard","I744";
;
CDS_LIB"mstr_standard"
BODY_TYPE"PLUMBING"
HDL_TAP"TRUE";
"B \NAC \NWC"2;
"S \NAC"
BN"24"100;
%"TAP"
"1","(-3025,2750)","0","mstr_standard","I745";
;
CDS_LIB"mstr_standard"
BODY_TYPE"PLUMBING"
HDL_TAP"TRUE";
"B \NAC \NWC"2;
"S \NAC"
BN"28"96;
%"TAP"
"1","(-3025,2800)","0","mstr_standard","I746";
;
CDS_LIB"mstr_standard"
BODY_TYPE"PLUMBING"
HDL_TAP"TRUE";
"B \NAC \NWC"2;
"S \NAC"
BN"27"97;
%"TAP"
"1","(-3025,2600)","0","mstr_standard","I747";
;
CDS_LIB"mstr_standard"
BODY_TYPE"PLUMBING"
HDL_TAP"TRUE";
"B \NAC \NWC"2;
"S \NAC"
BN"31"102;
%"TAP"
"1","(-3025,2650)","0","mstr_standard","I748";
;
CDS_LIB"mstr_standard"
BODY_TYPE"PLUMBING"
HDL_TAP"TRUE";
"B \NAC \NWC"2;
"S \NAC"
BN"30"103;
%"TAP"
"1","(-3025,2700)","0","mstr_standard","I749";
;
CDS_LIB"mstr_standard"
BODY_TYPE"PLUMBING"
HDL_TAP"TRUE";
"B \NAC \NWC"2;
"S \NAC"
BN"29"104;
%"TAP"
"1","(-3025,2500)","0","mstr_standard","I750";
;
CDS_LIB"mstr_standard"
BODY_TYPE"PLUMBING"
HDL_TAP"TRUE";
"B \NAC \NWC"10;
"S \NAC"
BN"0"95;
%"TAP"
"1","(-3025,2400)","0","mstr_standard","I751";
;
CDS_LIB"mstr_standard"
BODY_TYPE"PLUMBING"
HDL_TAP"TRUE";
"B \NAC \NWC"10;
"S \NAC"
BN"2"93;
%"TAP"
"1","(-3025,2450)","0","mstr_standard","I752";
;
CDS_LIB"mstr_standard"
BODY_TYPE"PLUMBING"
HDL_TAP"TRUE";
"B \NAC \NWC"10;
"S \NAC"
BN"1"94;
%"TAP"
"1","(-3025,2350)","0","mstr_standard","I753";
;
CDS_LIB"mstr_standard"
BODY_TYPE"PLUMBING"
HDL_TAP"TRUE";
"B \NAC \NWC"10;
"S \NAC"
BN"3"92;
%"TAP"
"1","(-3025,2300)","0","mstr_standard","I754";
;
CDS_LIB"mstr_standard"
BODY_TYPE"PLUMBING"
HDL_TAP"TRUE";
"B \NAC \NWC"10;
"S \NAC"
BN"4"91;
%"TAP"
"1","(-3025,2250)","0","mstr_standard","I755";
;
CDS_LIB"mstr_standard"
BODY_TYPE"PLUMBING"
HDL_TAP"TRUE";
"B \NAC \NWC"10;
"S \NAC"
BN"5"90;
%"TAP"
"1","(-3025,2050)","0","mstr_standard","I756";
;
CDS_LIB"mstr_standard"
BODY_TYPE"PLUMBING"
HDL_TAP"TRUE";
"B \NAC \NWC"3;
"S \NAC"
BN"0"89;
%"TAP"
"1","(-3025,2150)","0","mstr_standard","I757";
;
CDS_LIB"mstr_standard"
BODY_TYPE"PLUMBING"
HDL_TAP"TRUE";
"B \NAC \NWC"10;
"S \NAC"
BN"7"87;
%"TAP"
"1","(-3025,2200)","0","mstr_standard","I758";
;
CDS_LIB"mstr_standard"
BODY_TYPE"PLUMBING"
HDL_TAP"TRUE";
"B \NAC \NWC"10;
"S \NAC"
BN"6"88;
%"TAP"
"1","(-3025,2000)","0","mstr_standard","I759";
;
CDS_LIB"mstr_standard"
BODY_TYPE"PLUMBING"
HDL_TAP"TRUE";
"B \NAC \NWC"3;
"S \NAC"
BN"1"86;
%"TAP"
"1","(-3025,1950)","0","mstr_standard","I760";
;
CDS_LIB"mstr_standard"
BODY_TYPE"PLUMBING"
HDL_TAP"TRUE";
"B \NAC \NWC"3;
"S \NAC"
BN"2"85;
%"TAP"
"1","(-3025,1900)","0","mstr_standard","I761";
;
CDS_LIB"mstr_standard"
BODY_TYPE"PLUMBING"
HDL_TAP"TRUE";
"B \NAC \NWC"3;
"S \NAC"
BN"3"84;
%"TAP"
"1","(-3025,1850)","0","mstr_standard","I762";
;
CDS_LIB"mstr_standard"
BODY_TYPE"PLUMBING"
HDL_TAP"TRUE";
"B \NAC \NWC"3;
"S \NAC"
BN"4"83;
%"TAP"
"1","(-3025,1800)","0","mstr_standard","I763";
;
CDS_LIB"mstr_standard"
BODY_TYPE"PLUMBING"
HDL_TAP"TRUE";
"B \NAC \NWC"3;
"S \NAC"
BN"5"82;
%"TAP"
"1","(-3025,1750)","0","mstr_standard","I764";
;
CDS_LIB"mstr_standard"
BODY_TYPE"PLUMBING"
HDL_TAP"TRUE";
"B \NAC \NWC"3;
"S \NAC"
BN"6"81;
%"TAP"
"1","(-3025,1700)","0","mstr_standard","I765";
;
CDS_LIB"mstr_standard"
BODY_TYPE"PLUMBING"
HDL_TAP"TRUE";
"B \NAC \NWC"3;
"S \NAC"
BN"7"80;
%"TAP"
"1","(-5550,6100)","2","mstr_standard","I766";
;
CDS_LIB"mstr_standard"
BODY_TYPE"PLUMBING"
HDL_TAP"TRUE";
"B \NAC \NWC"4;
"S \NAC"
BN"0"79;
%"TAP"
"1","(-5550,6000)","2","mstr_standard","I767";
;
CDS_LIB"mstr_standard"
BODY_TYPE"PLUMBING"
HDL_TAP"TRUE";
"B \NAC \NWC"4;
"S \NAC"
BN"1"78;
%"TAP"
"1","(-5550,5900)","2","mstr_standard","I768";
;
CDS_LIB"mstr_standard"
BODY_TYPE"PLUMBING"
HDL_TAP"TRUE";
"B \NAC \NWC"4;
"S \NAC"
BN"2"77;
%"TAP"
"1","(-5550,5800)","2","mstr_standard","I769";
;
CDS_LIB"mstr_standard"
BODY_TYPE"PLUMBING"
HDL_TAP"TRUE";
"B \NAC \NWC"4;
"S \NAC"
BN"3"76;
%"TAP"
"1","(-5550,5700)","2","mstr_standard","I770";
;
CDS_LIB"mstr_standard"
BODY_TYPE"PLUMBING"
HDL_TAP"TRUE";
"B \NAC \NWC"4;
"S \NAC"
BN"4"75;
%"TAP"
"1","(-5550,5600)","2","mstr_standard","I771";
;
CDS_LIB"mstr_standard"
BODY_TYPE"PLUMBING"
HDL_TAP"TRUE";
"B \NAC \NWC"4;
"S \NAC"
BN"5"71;
%"TAP"
"1","(-5550,5500)","2","mstr_standard","I772";
;
CDS_LIB"mstr_standard"
BODY_TYPE"PLUMBING"
HDL_TAP"TRUE";
"B \NAC \NWC"4;
"S \NAC"
BN"6"70;
%"TAP"
"1","(-5550,5400)","2","mstr_standard","I773";
;
CDS_LIB"mstr_standard"
BODY_TYPE"PLUMBING"
HDL_TAP"TRUE";
"B \NAC \NWC"4;
"S \NAC"
BN"7"74;
%"TAP"
"1","(-5550,5300)","2","mstr_standard","I774";
;
CDS_LIB"mstr_standard"
BODY_TYPE"PLUMBING"
HDL_TAP"TRUE";
"B \NAC \NWC"4;
"S \NAC"
BN"8"73;
%"TAP"
"1","(-5550,5200)","2","mstr_standard","I775";
;
CDS_LIB"mstr_standard"
BODY_TYPE"PLUMBING"
HDL_TAP"TRUE";
"B \NAC \NWC"4;
"S \NAC"
BN"9"72;
%"TAP"
"1","(-5750,5950)","2","mstr_standard","I776";
;
CDS_LIB"mstr_standard"
BODY_TYPE"PLUMBING"
HDL_TAP"TRUE";
"B \NAC \NWC"5;
"S \NAC"
BN"1"68;
%"TAP"
"1","(-5750,6050)","2","mstr_standard","I777";
;
CDS_LIB"mstr_standard"
BODY_TYPE"PLUMBING"
HDL_TAP"TRUE";
"B \NAC \NWC"5;
"S \NAC"
BN"0"69;
%"TAP"
"1","(-5750,5650)","2","mstr_standard","I778";
;
CDS_LIB"mstr_standard"
BODY_TYPE"PLUMBING"
HDL_TAP"TRUE";
"B \NAC \NWC"5;
"S \NAC"
BN"4"64;
%"TAP"
"1","(-5750,5750)","2","mstr_standard","I779";
;
CDS_LIB"mstr_standard"
BODY_TYPE"PLUMBING"
HDL_TAP"TRUE";
"B \NAC \NWC"5;
"S \NAC"
BN"3"65;
%"TAP"
"1","(-5750,5850)","2","mstr_standard","I780";
;
CDS_LIB"mstr_standard"
BODY_TYPE"PLUMBING"
HDL_TAP"TRUE";
"B \NAC \NWC"5;
"S \NAC"
BN"2"66;
%"TAP"
"1","(-5750,5450)","2","mstr_standard","I781";
;
CDS_LIB"mstr_standard"
BODY_TYPE"PLUMBING"
HDL_TAP"TRUE";
"B \NAC \NWC"5;
"S \NAC"
BN"6"62;
%"TAP"
"1","(-5750,5550)","2","mstr_standard","I782";
;
CDS_LIB"mstr_standard"
BODY_TYPE"PLUMBING"
HDL_TAP"TRUE";
"B \NAC \NWC"5;
"S \NAC"
BN"5"63;
%"TAP"
"1","(-5750,5150)","2","mstr_standard","I783";
;
CDS_LIB"mstr_standard"
BODY_TYPE"PLUMBING"
HDL_TAP"TRUE";
"B \NAC \NWC"5;
"S \NAC"
BN"9"60;
%"TAP"
"1","(-5750,5250)","2","mstr_standard","I784";
;
CDS_LIB"mstr_standard"
BODY_TYPE"PLUMBING"
HDL_TAP"TRUE";
"B \NAC \NWC"5;
"S \NAC"
BN"8"61;
%"TAP"
"1","(-5750,5350)","2","mstr_standard","I785";
;
CDS_LIB"mstr_standard"
BODY_TYPE"PLUMBING"
HDL_TAP"TRUE";
"B \NAC \NWC"5;
"S \NAC"
BN"7"67;
%"TAP"
"1","(-5550,5050)","2","mstr_standard","I786";
;
CDS_LIB"mstr_standard"
BODY_TYPE"PLUMBING"
HDL_TAP"TRUE";
"B \NAC \NWC"6;
"S \NAC"
BN"0"55;
%"TAP"
"1","(-5550,4950)","2","mstr_standard","I787";
;
CDS_LIB"mstr_standard"
BODY_TYPE"PLUMBING"
HDL_TAP"TRUE";
"B \NAC \NWC"6;
"S \NAC"
BN"1"59;
%"TAP"
"1","(-5550,4750)","2","mstr_standard","I788";
;
CDS_LIB"mstr_standard"
BODY_TYPE"PLUMBING"
HDL_TAP"TRUE";
"B \NAC \NWC"6;
"S \NAC"
BN"3"57;
%"TAP"
"1","(-5550,4850)","2","mstr_standard","I789";
;
CDS_LIB"mstr_standard"
BODY_TYPE"PLUMBING"
HDL_TAP"TRUE";
"B \NAC \NWC"6;
"S \NAC"
BN"2"58;
%"TAP"
"1","(-5550,4650)","2","mstr_standard","I790";
;
CDS_LIB"mstr_standard"
BODY_TYPE"PLUMBING"
HDL_TAP"TRUE";
"B \NAC \NWC"6;
"S \NAC"
BN"4"56;
%"TAP"
"1","(-5550,4550)","2","mstr_standard","I791";
;
CDS_LIB"mstr_standard"
BODY_TYPE"PLUMBING"
HDL_TAP"TRUE";
"B \NAC \NWC"6;
"S \NAC"
BN"5"54;
%"TAP"
"1","(-5550,4450)","2","mstr_standard","I792";
;
CDS_LIB"mstr_standard"
BODY_TYPE"PLUMBING"
HDL_TAP"TRUE";
"B \NAC \NWC"6;
"S \NAC"
BN"6"53;
%"TAP"
"1","(-5550,4350)","2","mstr_standard","I793";
;
CDS_LIB"mstr_standard"
BODY_TYPE"PLUMBING"
HDL_TAP"TRUE";
"B \NAC \NWC"6;
"S \NAC"
BN"7"52;
%"TAP"
"1","(-5550,4250)","2","mstr_standard","I794";
;
CDS_LIB"mstr_standard"
BODY_TYPE"PLUMBING"
HDL_TAP"TRUE";
"B \NAC \NWC"6;
"S \NAC"
BN"8"51;
%"TAP"
"1","(-5550,4150)","2","mstr_standard","I795";
;
CDS_LIB"mstr_standard"
BODY_TYPE"PLUMBING"
HDL_TAP"TRUE";
"B \NAC \NWC"6;
"S \NAC"
BN"9"50;
%"TAP"
"1","(-5750,4900)","2","mstr_standard","I796";
;
CDS_LIB"mstr_standard"
BODY_TYPE"PLUMBING"
HDL_TAP"TRUE";
"B \NAC \NWC"7;
"S \NAC"
BN"1"43;
%"TAP"
"1","(-5750,5000)","2","mstr_standard","I797";
;
CDS_LIB"mstr_standard"
BODY_TYPE"PLUMBING"
HDL_TAP"TRUE";
"B \NAC \NWC"7;
"S \NAC"
BN"0"44;
%"TAP"
"1","(-5750,4700)","2","mstr_standard","I798";
;
CDS_LIB"mstr_standard"
BODY_TYPE"PLUMBING"
HDL_TAP"TRUE";
"B \NAC \NWC"7;
"S \NAC"
BN"3"41;
%"TAP"
"1","(-5750,4800)","2","mstr_standard","I799";
;
CDS_LIB"mstr_standard"
BODY_TYPE"PLUMBING"
HDL_TAP"TRUE";
"B \NAC \NWC"7;
"S \NAC"
BN"2"42;
%"TAP"
"1","(-5750,4600)","2","mstr_standard","I800";
;
CDS_LIB"mstr_standard"
BODY_TYPE"PLUMBING"
HDL_TAP"TRUE";
"B \NAC \NWC"7;
"S \NAC"
BN"4"40;
%"TAP"
"1","(-5750,4400)","2","mstr_standard","I801";
;
CDS_LIB"mstr_standard"
BODY_TYPE"PLUMBING"
HDL_TAP"TRUE";
"B \NAC \NWC"7;
"S \NAC"
BN"6"48;
%"TAP"
"1","(-5750,4500)","2","mstr_standard","I802";
;
CDS_LIB"mstr_standard"
BODY_TYPE"PLUMBING"
HDL_TAP"TRUE";
"B \NAC \NWC"7;
"S \NAC"
BN"5"49;
%"TAP"
"1","(-5750,4100)","2","mstr_standard","I803";
;
CDS_LIB"mstr_standard"
BODY_TYPE"PLUMBING"
HDL_TAP"TRUE";
"B \NAC \NWC"7;
"S \NAC"
BN"9"45;
%"TAP"
"1","(-5750,4200)","2","mstr_standard","I804";
;
CDS_LIB"mstr_standard"
BODY_TYPE"PLUMBING"
HDL_TAP"TRUE";
"B \NAC \NWC"7;
"S \NAC"
BN"8"46;
%"TAP"
"1","(-5750,4300)","2","mstr_standard","I805";
;
CDS_LIB"mstr_standard"
BODY_TYPE"PLUMBING"
HDL_TAP"TRUE";
"B \NAC \NWC"7;
"S \NAC"
BN"7"47;
%"TAP"
"1","(-5700,3900)","2","mstr_standard","I810";
;
CDS_LIB"mstr_standard"
BODY_TYPE"PLUMBING"
HDL_TAP"TRUE";
"B \NAC \NWC"8;
"S \NAC"
BN"1"37;
%"TAP"
"1","(-5700,3950)","2","mstr_standard","I811";
;
CDS_LIB"mstr_standard"
BODY_TYPE"PLUMBING"
HDL_TAP"TRUE";
"B \NAC \NWC"8;
"S \NAC"
BN"0"39;
%"TAP"
"1","(-5700,3850)","2","mstr_standard","I812";
;
CDS_LIB"mstr_standard"
BODY_TYPE"PLUMBING"
HDL_TAP"TRUE";
"B \NAC \NWC"8;
"S \NAC"
BN"2"35;
%"TAP"
"1","(-5700,3750)","2","mstr_standard","I813";
;
CDS_LIB"mstr_standard"
BODY_TYPE"PLUMBING"
HDL_TAP"TRUE";
"B \NAC \NWC"8;
"S \NAC"
BN"4"31;
%"TAP"
"1","(-5700,3800)","2","mstr_standard","I814";
;
CDS_LIB"mstr_standard"
BODY_TYPE"PLUMBING"
HDL_TAP"TRUE";
"B \NAC \NWC"8;
"S \NAC"
BN"3"33;
%"TAP"
"1","(-5700,3650)","2","mstr_standard","I815";
;
CDS_LIB"mstr_standard"
BODY_TYPE"PLUMBING"
HDL_TAP"TRUE";
"B \NAC \NWC"8;
"S \NAC"
BN"6"27;
%"TAP"
"1","(-5700,3700)","2","mstr_standard","I816";
;
CDS_LIB"mstr_standard"
BODY_TYPE"PLUMBING"
HDL_TAP"TRUE";
"B \NAC \NWC"8;
"S \NAC"
BN"5"29;
%"TAP"
"1","(-5700,3500)","2","mstr_standard","I817";
;
CDS_LIB"mstr_standard"
BODY_TYPE"PLUMBING"
HDL_TAP"TRUE";
"B \NAC \NWC"9;
"S \NAC"
BN"1"36;
%"TAP"
"1","(-5700,3550)","2","mstr_standard","I818";
;
CDS_LIB"mstr_standard"
BODY_TYPE"PLUMBING"
HDL_TAP"TRUE";
"B \NAC \NWC"9;
"S \NAC"
BN"0"38;
%"TAP"
"1","(-5700,3350)","2","mstr_standard","I819";
;
CDS_LIB"mstr_standard"
BODY_TYPE"PLUMBING"
HDL_TAP"TRUE";
"B \NAC \NWC"9;
"S \NAC"
BN"4"30;
%"TAP"
"1","(-5700,3400)","2","mstr_standard","I820";
;
CDS_LIB"mstr_standard"
BODY_TYPE"PLUMBING"
HDL_TAP"TRUE";
"B \NAC \NWC"9;
"S \NAC"
BN"3"32;
%"TAP"
"1","(-5700,3450)","2","mstr_standard","I821";
;
CDS_LIB"mstr_standard"
BODY_TYPE"PLUMBING"
HDL_TAP"TRUE";
"B \NAC \NWC"9;
"S \NAC"
BN"2"34;
%"TAP"
"1","(-5700,3250)","2","mstr_standard","I822";
;
CDS_LIB"mstr_standard"
BODY_TYPE"PLUMBING"
HDL_TAP"TRUE";
"B \NAC \NWC"9;
"S \NAC"
BN"6"26;
%"TAP"
"1","(-5700,3300)","2","mstr_standard","I823";
;
CDS_LIB"mstr_standard"
BODY_TYPE"PLUMBING"
HDL_TAP"TRUE";
"B \NAC \NWC"9;
"S \NAC"
BN"5"28;
%"Q_RES"
"1","(-6600,2250)","0","pure_quanta","I837";
;
LOCATION"R375"
$SEC"1"
CDS_SEC"1"
TOLERANCE"1%"
VALUE"15   "
PART_NUMBER"CS01502FB11"
PACK_TYPE"0402LF"
CDS_LIB"pure_quanta"
WATTAGE"1/16W"
MATERIAL"CHIP";
"B"
$PN"2"14;
"A"
$PN"1"11;
END.
